(kicad_pcb
	(version 20260206)
	(generator "pcbnew")
	(generator_version "10.0")
	(general
		(thickness 1.6)
		(legacy_teardrops no)
	)
	(paper "A4")
	(title_block
		(title "04192023_DAF0TMB3IC0_F0TG_MB_C_brd_V02_OCP.brd")
		(comment 1 "Grand Teton / footprint 3955 of 8354 (U25), pads 2332-2446 of 6102")
	)
	(layers
		(0 "F.Cu" signal "TOP")
		(4 "In1.Cu" signal "GND")
		(6 "In2.Cu" signal "IN1")
		(8 "In3.Cu" signal "GND1")
		(10 "In4.Cu" signal "IN2")
		(12 "In5.Cu" signal "GND2")
		(14 "In6.Cu" signal "IN3")
		(16 "In7.Cu" signal "GND3")
		(18 "In8.Cu" signal "VCC")
		(20 "In9.Cu" signal "VCC1")
		(22 "In10.Cu" signal "GND4")
		(24 "In11.Cu" signal "IN4")
		(26 "In12.Cu" signal "GND5")
		(28 "In13.Cu" signal "IN5")
		(30 "In14.Cu" signal "GND6")
		(32 "In15.Cu" signal "IN6")
		(34 "In16.Cu" signal "GND7")
		(2 "B.Cu" signal "BOTTOM")
		(9 "F.Adhes" user "F.Adhesive")
		(11 "B.Adhes" user "B.Adhesive")
		(13 "F.Paste" user "Package Geometry/Pastemask Top")
		(15 "B.Paste" user "Package Geometry/Pastemask Bottom")
		(5 "F.SilkS" user "Ref Des/Silkscreen Top")
		(7 "B.SilkS" user "Ref Des/Silkscreen Bottom")
		(1 "F.Mask" user "Board Geometry/Soldermask Top")
		(3 "B.Mask" user "Board Geometry/Soldermask Bottom")
		(17 "Dwgs.User" user "User.Drawings")
		(19 "Cmts.User" user "User.Comments")
		(21 "Eco1.User" user "User.Eco1")
		(23 "Eco2.User" user "User.Eco2")
		(25 "Edge.Cuts" user "Board Geometry/Outline")
		(27 "Margin" user)
		(31 "F.CrtYd" user "Package Geometry/Place Bound Top")
		(29 "B.CrtYd" user "Package Geometry/Place Bound Bottom")
		(35 "F.Fab" user "Ref Des/Assembly Top")
		(33 "B.Fab" user "Ref Des/Assembly Bottom")
	)
	(footprint ""
		(layer "F.Cu")
		(at 359.867962 -258.880102 180)
		(property "Reference" "U25"
			(at -45.78477 -62.086744 0)
			(unlocked yes)
			(layer "F.SilkS")
			(effects
				(font
					(size 0.7874 0.5842)
					(thickness 0.1524)
				)
			)
		)
		(property "Value" ""
			(at 0 0 180)
			(layer "F.Fab")
			(effects
				(font
					(size 1.27 1.27)
				)
			)
		)
		(duplicate_pad_numbers_are_jumpers no)
		(pad "BR28" smd circle
			(at -9.079992 9.269984 180)
			(size 0.450088 0.450088)
			(layers "F.Cu" "F.Mask" "F.Paste")
			(net "GND")
		)
		(pad "BR29" smd circle
			(at -8.139938 9.269984 180)
			(size 0.450088 0.450088)
			(layers "F.Cu" "F.Mask" "F.Paste")
			(net "PVDDCR_CPU1_P0")
		)
		(pad "BR30" smd circle
			(at -7.199884 9.269984 180)
			(size 0.450088 0.450088)
			(layers "F.Cu" "F.Mask" "F.Paste")
			(net "GND")
		)
		(pad "BR31" smd circle
			(at -6.260084 9.269984 180)
			(size 0.450088 0.450088)
			(layers "F.Cu" "F.Mask" "F.Paste")
			(net "PVDDCR_CPU1_P0")
		)
		(pad "BR32" smd circle
			(at -5.32003 9.269984 180)
			(size 0.450088 0.450088)
			(layers "F.Cu" "F.Mask" "F.Paste")
			(net "GND")
		)
		(pad "BR33" smd circle
			(at -4.379976 9.269984 180)
			(size 0.450088 0.450088)
			(layers "F.Cu" "F.Mask" "F.Paste")
			(net "PVDDCR_CPU1_P0")
		)
		(pad "BR34" smd circle
			(at -3.439922 9.269984 180)
			(size 0.450088 0.450088)
			(layers "F.Cu" "F.Mask" "F.Paste")
			(net "GND")
		)
		(pad "BR35" smd circle
			(at -2.500122 9.269984 180)
			(size 0.450088 0.450088)
			(layers "F.Cu" "F.Mask" "F.Paste")
			(net "PVDDCR_CPU1_P0")
		)
		(pad "BR36" smd circle
			(at -1.560068 9.269984 180)
			(size 0.450088 0.450088)
			(layers "F.Cu" "F.Mask" "F.Paste")
			(net "GND")
		)
		(pad "BR40" smd circle
			(at 1.260094 9.269984 180)
			(size 0.450088 0.450088)
			(layers "F.Cu" "F.Mask" "F.Paste")
			(net "PVDDCR_CPU1_P0")
		)
		(pad "BR41" smd circle
			(at 2.199894 9.269984 180)
			(size 0.450088 0.450088)
			(layers "F.Cu" "F.Mask" "F.Paste")
			(net "GND")
		)
		(pad "BR42" smd circle
			(at 3.139948 9.269984 180)
			(size 0.450088 0.450088)
			(layers "F.Cu" "F.Mask" "F.Paste")
			(net "PVDDCR_CPU1_P0")
		)
		(pad "BR43" smd circle
			(at 4.080002 9.269984 180)
			(size 0.450088 0.450088)
			(layers "F.Cu" "F.Mask" "F.Paste")
			(net "GND")
		)
		(pad "BR44" smd circle
			(at 5.020056 9.269984 180)
			(size 0.450088 0.450088)
			(layers "F.Cu" "F.Mask" "F.Paste")
			(net "PVDDCR_CPU1_P0")
		)
		(pad "BR45" smd circle
			(at 5.96011 9.269984 180)
			(size 0.450088 0.450088)
			(layers "F.Cu" "F.Mask" "F.Paste")
			(net "GND")
		)
		(pad "BR46" smd circle
			(at 6.89991 9.269984 180)
			(size 0.450088 0.450088)
			(layers "F.Cu" "F.Mask" "F.Paste")
			(net "PVDDCR_CPU1_P0")
		)
		(pad "BR47" smd circle
			(at 7.839964 9.269984 180)
			(size 0.450088 0.450088)
			(layers "F.Cu" "F.Mask" "F.Paste")
			(net "GND")
		)
		(pad "BR48" smd circle
			(at 8.780018 9.269984 180)
			(size 0.450088 0.450088)
			(layers "F.Cu" "F.Mask" "F.Paste")
			(net "PVDDCR_CPU1_P0")
		)
		(pad "BR49" smd circle
			(at 9.720072 9.269984 180)
			(size 0.450088 0.450088)
			(layers "F.Cu" "F.Mask" "F.Paste")
			(net "GND")
		)
		(pad "BR50" smd circle
			(at 10.659872 9.269984 180)
			(size 0.450088 0.450088)
			(layers "F.Cu" "F.Mask" "F.Paste")
			(net "PVDDCR_CPU1_P0")
		)
		(pad "BR51" smd circle
			(at 11.599926 9.269984 180)
			(size 0.450088 0.450088)
			(layers "F.Cu" "F.Mask" "F.Paste")
			(net "GND")
		)
		(pad "BR52" smd circle
			(at 12.53998 9.269984 180)
			(size 0.450088 0.450088)
			(layers "F.Cu" "F.Mask" "F.Paste")
			(net "PVDDCR_CPU1_P0")
		)
		(pad "BR53" smd circle
			(at 13.480034 9.269984 180)
			(size 0.450088 0.450088)
			(layers "F.Cu" "F.Mask" "F.Paste")
			(net "VSENSE_PVDDIO_P0_DP")
		)
		(pad "BR54" smd circle
			(at 14.420088 9.269984 180)
			(size 0.450088 0.450088)
			(layers "F.Cu" "F.Mask" "F.Paste")
			(net "VSENSE_VSS_SENSE_B_P0")
		)
		(pad "BR55" smd circle
			(at 15.359888 9.269984 180)
			(size 0.450088 0.450088)
			(layers "F.Cu" "F.Mask" "F.Paste")
			(net "GND")
		)
		(pad "BR56" smd circle
			(at 16.299942 9.269984 180)
			(size 0.450088 0.450088)
			(layers "F.Cu" "F.Mask" "F.Paste")
			(net "GND")
		)
		(pad "BR57" smd circle
			(at 17.239996 9.269984 180)
			(size 0.450088 0.450088)
			(layers "F.Cu" "F.Mask" "F.Paste")
			(net "Net_1810")
		)
		(pad "BR58" smd circle
			(at 18.18005 9.269984 180)
			(size 0.450088 0.450088)
			(layers "F.Cu" "F.Mask" "F.Paste")
			(net "PVDDIO_P0")
		)
		(pad "BR59" smd circle
			(at 19.120104 9.269984 180)
			(size 0.450088 0.450088)
			(layers "F.Cu" "F.Mask" "F.Paste")
			(net "GND")
		)
		(pad "BR60" smd circle
			(at 20.059904 9.269984 180)
			(size 0.450088 0.450088)
			(layers "F.Cu" "F.Mask" "F.Paste")
			(net "Net_1818")
		)
		(pad "BR61" smd circle
			(at 20.999958 9.269984 180)
			(size 0.450088 0.450088)
			(layers "F.Cu" "F.Mask" "F.Paste")
			(net "GND")
		)
		(pad "BR62" smd circle
			(at 21.940012 9.269984 180)
			(size 0.450088 0.450088)
			(layers "F.Cu" "F.Mask" "F.Paste")
			(net "GND")
		)
		(pad "BR63" smd circle
			(at 22.880066 9.269984 180)
			(size 0.450088 0.450088)
			(layers "F.Cu" "F.Mask" "F.Paste")
			(net "GND")
		)
		(pad "BR64" smd circle
			(at 23.82012 9.269984 180)
			(size 0.450088 0.450088)
			(layers "F.Cu" "F.Mask" "F.Paste")
			(net "Net_1802")
		)
		(pad "BR65" smd circle
			(at 24.75992 9.269984 180)
			(size 0.450088 0.450088)
			(layers "F.Cu" "F.Mask" "F.Paste")
			(net "PVDDIO_P0")
		)
		(pad "BR66" smd circle
			(at 25.699974 9.269984 180)
			(size 0.450088 0.450088)
			(layers "F.Cu" "F.Mask" "F.Paste")
			(net "GND")
		)
		(pad "BR67" smd circle
			(at 26.640028 9.269984 180)
			(size 0.450088 0.450088)
			(layers "F.Cu" "F.Mask" "F.Paste")
			(net "Net_1834")
		)
		(pad "BR68" smd circle
			(at 27.580082 9.269984 180)
			(size 0.450088 0.450088)
			(layers "F.Cu" "F.Mask" "F.Paste")
			(net "GND")
		)
		(pad "BR69" smd circle
			(at 28.519882 9.269984 180)
			(size 0.450088 0.450088)
			(layers "F.Cu" "F.Mask" "F.Paste")
			(net "GND")
		)
		(pad "BR70" smd circle
			(at 29.459936 9.269984 180)
			(size 0.450088 0.450088)
			(layers "F.Cu" "F.Mask" "F.Paste")
			(net "GND")
		)
		(pad "BR71" smd circle
			(at 30.39999 9.269984 180)
			(size 0.450088 0.450088)
			(layers "F.Cu" "F.Mask" "F.Paste")
			(net "Net_1826")
		)
		(pad "BR72" smd circle
			(at 31.340044 9.269984 180)
			(size 0.450088 0.450088)
			(layers "F.Cu" "F.Mask" "F.Paste")
			(net "PVDDIO_P0")
		)
		(pad "BR73" smd circle
			(at 32.280098 9.269984 180)
			(size 0.450088 0.450088)
			(layers "F.Cu" "F.Mask" "F.Paste")
			(net "GND")
		)
		(pad "BR74" smd circle
			(at 33.219898 9.269984 180)
			(size 0.450088 0.450088)
			(layers "F.Cu" "F.Mask" "F.Paste")
			(net "Net_1794")
		)
		(pad "BR75" smd circle
			(at 34.159952 9.269984 180)
			(size 0.450088 0.450088)
			(layers "F.Cu" "F.Mask" "F.Paste")
			(net "GND")
		)
		(pad "BT2" smd circle
			(at -33.990026 10.07999 180)
			(size 0.450088 0.450088)
			(layers "F.Cu" "F.Mask" "F.Paste")
			(net "M_G_CPU0_SB_CB<4>")
		)
		(pad "BT3" smd circle
			(at -33.049972 10.07999 180)
			(size 0.450088 0.450088)
			(layers "F.Cu" "F.Mask" "F.Paste")
			(net "GND")
		)
		(pad "BT4" smd circle
			(at -32.109918 10.07999 180)
			(size 0.450088 0.450088)
			(layers "F.Cu" "F.Mask" "F.Paste")
			(net "GND")
		)
		(pad "BT5" smd circle
			(at -31.170118 10.07999 180)
			(size 0.450088 0.450088)
			(layers "F.Cu" "F.Mask" "F.Paste")
			(net "GND")
		)
		(pad "BT6" smd circle
			(at -30.230064 10.07999 180)
			(size 0.450088 0.450088)
			(layers "F.Cu" "F.Mask" "F.Paste")
			(net "M_K_CPU0_SB_CB<4>")
		)
		(pad "BT7" smd circle
			(at -29.29001 10.07999 180)
			(size 0.450088 0.450088)
			(layers "F.Cu" "F.Mask" "F.Paste")
			(net "GND")
		)
		(pad "BT8" smd circle
			(at -28.349956 10.07999 180)
			(size 0.450088 0.450088)
			(layers "F.Cu" "F.Mask" "F.Paste")
			(net "GND")
		)
		(pad "BT9" smd circle
			(at -27.409902 10.07999 180)
			(size 0.450088 0.450088)
			(layers "F.Cu" "F.Mask" "F.Paste")
			(net "M_L_CPU0_SB_CB<4>")
		)
		(pad "BT10" smd circle
			(at -26.470102 10.07999 180)
			(size 0.450088 0.450088)
			(layers "F.Cu" "F.Mask" "F.Paste")
			(net "GND")
		)
		(pad "BT11" smd circle
			(at -25.530048 10.07999 180)
			(size 0.450088 0.450088)
			(layers "F.Cu" "F.Mask" "F.Paste")
			(net "GND")
		)
		(pad "BT12" smd circle
			(at -24.589994 10.07999 180)
			(size 0.450088 0.450088)
			(layers "F.Cu" "F.Mask" "F.Paste")
			(net "GND")
		)
		(pad "BT13" smd circle
			(at -23.64994 10.07999 180)
			(size 0.450088 0.450088)
			(layers "F.Cu" "F.Mask" "F.Paste")
			(net "M_H_CPU0_SB_CB<4>")
		)
		(pad "BT14" smd circle
			(at -22.709886 10.07999 180)
			(size 0.450088 0.450088)
			(layers "F.Cu" "F.Mask" "F.Paste")
			(net "GND")
		)
		(pad "BT15" smd circle
			(at -21.770086 10.07999 180)
			(size 0.450088 0.450088)
			(layers "F.Cu" "F.Mask" "F.Paste")
			(net "GND")
		)
		(pad "BT16" smd circle
			(at -20.830032 10.07999 180)
			(size 0.450088 0.450088)
			(layers "F.Cu" "F.Mask" "F.Paste")
			(net "M_J_CPU0_SB_CB<4>")
		)
		(pad "BT17" smd circle
			(at -19.889978 10.07999 180)
			(size 0.450088 0.450088)
			(layers "F.Cu" "F.Mask" "F.Paste")
			(net "GND")
		)
		(pad "BT18" smd circle
			(at -18.949924 10.07999 180)
			(size 0.450088 0.450088)
			(layers "F.Cu" "F.Mask" "F.Paste")
			(net "GND")
		)
		(pad "BT19" smd circle
			(at -18.010124 10.07999 180)
			(size 0.450088 0.450088)
			(layers "F.Cu" "F.Mask" "F.Paste")
			(net "GND")
		)
		(pad "BT20" smd circle
			(at -17.07007 10.07999 180)
			(size 0.450088 0.450088)
			(layers "F.Cu" "F.Mask" "F.Paste")
			(net "M_I_CPU0_SB_CB<4>")
		)
		(pad "BT21" smd circle
			(at -16.130016 10.07999 180)
			(size 0.450088 0.450088)
			(layers "F.Cu" "F.Mask" "F.Paste")
			(net "GND")
		)
		(pad "BT22" smd circle
			(at -15.189962 10.07999 180)
			(size 0.450088 0.450088)
			(layers "F.Cu" "F.Mask" "F.Paste")
			(net "GND")
		)
		(pad "BT23" smd circle
			(at -14.249908 10.07999 180)
			(size 0.450088 0.450088)
			(layers "F.Cu" "F.Mask" "F.Paste")
			(net "PVDDCR_CPU1_P0")
		)
		(pad "BT24" smd circle
			(at -13.310108 10.07999 180)
			(size 0.450088 0.450088)
			(layers "F.Cu" "F.Mask" "F.Paste")
			(net "PVDDCR_CPU1_P0")
		)
		(pad "BT25" smd circle
			(at -12.370054 10.07999 180)
			(size 0.450088 0.450088)
			(layers "F.Cu" "F.Mask" "F.Paste")
			(net "GND")
		)
		(pad "BT26" smd circle
			(at -11.43 10.07999 180)
			(size 0.450088 0.450088)
			(layers "F.Cu" "F.Mask" "F.Paste")
			(net "PVDDCR_CPU1_P0")
		)
		(pad "BT27" smd circle
			(at -10.489946 10.07999 180)
			(size 0.450088 0.450088)
			(layers "F.Cu" "F.Mask" "F.Paste")
			(net "PVDDCR_CPU1_P0")
		)
		(pad "BT28" smd circle
			(at -9.549892 10.07999 180)
			(size 0.450088 0.450088)
			(layers "F.Cu" "F.Mask" "F.Paste")
			(net "GND")
		)
		(pad "BT29" smd circle
			(at -8.610092 10.07999 180)
			(size 0.450088 0.450088)
			(layers "F.Cu" "F.Mask" "F.Paste")
			(net "PVDDCR_CPU1_P0")
		)
		(pad "BT30" smd circle
			(at -7.670038 10.07999 180)
			(size 0.450088 0.450088)
			(layers "F.Cu" "F.Mask" "F.Paste")
			(net "PVDDCR_CPU1_P0")
		)
		(pad "BT31" smd circle
			(at -6.729984 10.07999 180)
			(size 0.450088 0.450088)
			(layers "F.Cu" "F.Mask" "F.Paste")
			(net "GND")
		)
		(pad "BT32" smd circle
			(at -5.78993 10.07999 180)
			(size 0.450088 0.450088)
			(layers "F.Cu" "F.Mask" "F.Paste")
			(net "PVDDCR_CPU1_P0")
		)
		(pad "BT33" smd circle
			(at -4.849876 10.07999 180)
			(size 0.450088 0.450088)
			(layers "F.Cu" "F.Mask" "F.Paste")
			(net "PVDDCR_CPU1_P0")
		)
		(pad "BT34" smd circle
			(at -3.910076 10.07999 180)
			(size 0.450088 0.450088)
			(layers "F.Cu" "F.Mask" "F.Paste")
			(net "GND")
		)
		(pad "BT35" smd circle
			(at -2.970022 10.07999 180)
			(size 0.450088 0.450088)
			(layers "F.Cu" "F.Mask" "F.Paste")
			(net "P5E_CPU0_P2_TX_DN<0>")
		)
		(pad "BT36" smd circle
			(at -2.029968 10.07999 180)
			(size 0.450088 0.450088)
			(layers "F.Cu" "F.Mask" "F.Paste")
			(net "P5E_CPU0_P2_TX_DP<0>")
		)
		(pad "BT37" smd circle
			(at -1.089914 10.07999 180)
			(size 0.450088 0.450088)
			(layers "F.Cu" "F.Mask" "F.Paste")
			(net "GND")
		)
		(pad "BT39" smd circle
			(at 0.78994 10.07999 180)
			(size 0.450088 0.450088)
			(layers "F.Cu" "F.Mask" "F.Paste")
			(net "GND")
		)
		(pad "BT40" smd circle
			(at 1.729994 10.07999 180)
			(size 0.450088 0.450088)
			(layers "F.Cu" "F.Mask" "F.Paste")
			(net "P5E_CPU0_P0_RX_DP<15>")
		)
		(pad "BT41" smd circle
			(at 2.670048 10.07999 180)
			(size 0.450088 0.450088)
			(layers "F.Cu" "F.Mask" "F.Paste")
			(net "P5E_CPU0_P0_RX_DN<15>")
		)
		(pad "BT42" smd circle
			(at 3.610102 10.07999 180)
			(size 0.450088 0.450088)
			(layers "F.Cu" "F.Mask" "F.Paste")
			(net "GND")
		)
		(pad "BT43" smd circle
			(at 4.549902 10.07999 180)
			(size 0.450088 0.450088)
			(layers "F.Cu" "F.Mask" "F.Paste")
			(net "PVDDCR_CPU1_P0")
		)
		(pad "BT44" smd circle
			(at 5.489956 10.07999 180)
			(size 0.450088 0.450088)
			(layers "F.Cu" "F.Mask" "F.Paste")
			(net "PVDDCR_CPU1_P0")
		)
		(pad "BT45" smd circle
			(at 6.43001 10.07999 180)
			(size 0.450088 0.450088)
			(layers "F.Cu" "F.Mask" "F.Paste")
			(net "GND")
		)
		(pad "BT46" smd circle
			(at 7.370064 10.07999 180)
			(size 0.450088 0.450088)
			(layers "F.Cu" "F.Mask" "F.Paste")
			(net "PVDDCR_CPU1_P0")
		)
		(pad "BT47" smd circle
			(at 8.310118 10.07999 180)
			(size 0.450088 0.450088)
			(layers "F.Cu" "F.Mask" "F.Paste")
			(net "PVDDCR_CPU1_P0")
		)
		(pad "BT48" smd circle
			(at 9.249918 10.07999 180)
			(size 0.450088 0.450088)
			(layers "F.Cu" "F.Mask" "F.Paste")
			(net "GND")
		)
		(pad "BT49" smd circle
			(at 10.189972 10.07999 180)
			(size 0.450088 0.450088)
			(layers "F.Cu" "F.Mask" "F.Paste")
			(net "PVDDCR_CPU1_P0")
		)
		(pad "BT50" smd circle
			(at 11.130026 10.07999 180)
			(size 0.450088 0.450088)
			(layers "F.Cu" "F.Mask" "F.Paste")
			(net "PVDDCR_CPU1_P0")
		)
		(pad "BT51" smd circle
			(at 12.07008 10.07999 180)
			(size 0.450088 0.450088)
			(layers "F.Cu" "F.Mask" "F.Paste")
			(net "GND")
		)
		(pad "BT52" smd circle
			(at 13.00988 10.07999 180)
			(size 0.450088 0.450088)
			(layers "F.Cu" "F.Mask" "F.Paste")
			(net "PVDDCR_CPU1_P0")
		)
		(pad "BT53" smd circle
			(at 13.949934 10.07999 180)
			(size 0.450088 0.450088)
			(layers "F.Cu" "F.Mask" "F.Paste")
			(net "PVDDCR_CPU1_P0")
		)
		(pad "BT54" smd circle
			(at 14.889988 10.07999 180)
			(size 0.450088 0.450088)
			(layers "F.Cu" "F.Mask" "F.Paste")
			(net "GND")
		)
		(pad "BT55" smd circle
			(at 15.830042 10.07999 180)
			(size 0.450088 0.450088)
			(layers "F.Cu" "F.Mask" "F.Paste")
			(net "GND")
		)
		(pad "BT56" smd circle
			(at 16.770096 10.07999 180)
			(size 0.450088 0.450088)
			(layers "F.Cu" "F.Mask" "F.Paste")
			(net "M_C_CPU0_SB_CB<4>")
		)
		(pad "BT57" smd circle
			(at 17.709896 10.07999 180)
			(size 0.450088 0.450088)
			(layers "F.Cu" "F.Mask" "F.Paste")
			(net "GND")
		)
		(pad "BT58" smd circle
			(at 18.64995 10.07999 180)
			(size 0.450088 0.450088)
			(layers "F.Cu" "F.Mask" "F.Paste")
			(net "GND")
		)
		(pad "BT59" smd circle
			(at 19.590004 10.07999 180)
			(size 0.450088 0.450088)
			(layers "F.Cu" "F.Mask" "F.Paste")
			(net "GND")
		)
		(pad "BT60" smd circle
			(at 20.530058 10.07999 180)
			(size 0.450088 0.450088)
			(layers "F.Cu" "F.Mask" "F.Paste")
			(net "M_D_CPU0_SB_CB<4>")
		)
		(pad "BT61" smd circle
			(at 21.470112 10.07999 180)
			(size 0.450088 0.450088)
			(layers "F.Cu" "F.Mask" "F.Paste")
			(net "GND")
		)
		(pad "BT62" smd circle
			(at 22.409912 10.07999 180)
			(size 0.450088 0.450088)
			(layers "F.Cu" "F.Mask" "F.Paste")
			(net "GND")
		)
		(pad "BT63" smd circle
			(at 23.349966 10.07999 180)
			(size 0.450088 0.450088)
			(layers "F.Cu" "F.Mask" "F.Paste")
			(net "M_B_CPU0_SB_CB<4>")
		)
		(pad "BT64" smd circle
			(at 24.29002 10.07999 180)
			(size 0.450088 0.450088)
			(layers "F.Cu" "F.Mask" "F.Paste")
			(net "GND")
		)
		(pad "BT65" smd circle
			(at 25.230074 10.07999 180)
			(size 0.450088 0.450088)
			(layers "F.Cu" "F.Mask" "F.Paste")
			(net "GND")
		)
		(pad "BT66" smd circle
			(at 26.170128 10.07999 180)
			(size 0.450088 0.450088)
			(layers "F.Cu" "F.Mask" "F.Paste")
			(net "GND")
		)
		(pad "BT67" smd circle
			(at 27.109928 10.07999 180)
			(size 0.450088 0.450088)
			(layers "F.Cu" "F.Mask" "F.Paste")
			(net "M_F_CPU0_SB_CB<4>")
		)
		(pad "BT68" smd circle
			(at 28.049982 10.07999 180)
			(size 0.450088 0.450088)
			(layers "F.Cu" "F.Mask" "F.Paste")
			(net "GND")
		)
		(pad "BT69" smd circle
			(at 28.990036 10.07999 180)
			(size 0.450088 0.450088)
			(layers "F.Cu" "F.Mask" "F.Paste")
			(net "GND")
		)
		(pad "BT70" smd circle
			(at 29.93009 10.07999 180)
			(size 0.450088 0.450088)
			(layers "F.Cu" "F.Mask" "F.Paste")
			(net "M_E_CPU0_SB_CB<4>")
		)
		(pad "BT71" smd circle
			(at 30.86989 10.07999 180)
			(size 0.450088 0.450088)
			(layers "F.Cu" "F.Mask" "F.Paste")
			(net "GND")
		)
		(pad "BT72" smd circle
			(at 31.809944 10.07999 180)
			(size 0.450088 0.450088)
			(layers "F.Cu" "F.Mask" "F.Paste")
			(net "GND")
		)
	)
)
